#ISCELL
  mstr_symbols bom_note *
  *
#ISCELL
  mstr_symbols intel_corp_bpage *
  *
#ISCELL
  mstr_standard offpage *
  page81_i1
#ISCELL
  mstr_standard tap *
  page81_i10
#ISCELL
  mstr_standard tap *
  page81_i100
#ISCELL
  mstr_standard tap *
  page81_i101
#ISCELL
  mstr_standard tap *
  page81_i102
#ISCELL
  mstr_standard tap *
  page81_i103
#ISCELL
  mstr_standard tap *
  page81_i104
#ISCELL
  mstr_standard tap *
  page81_i105
#ISCELL
  mstr_standard tap *
  page81_i106
#ISCELL
  mstr_standard tap *
  page81_i107
#ISCELL
  mstr_standard tap *
  page81_i108
#ISCELL
  mstr_standard tap *
  page81_i109
#ISCELL
  mstr_standard tap *
  page81_i11
#ISCELL
  mstr_standard tap *
  page81_i110
#ISCELL
  mstr_standard tap *
  page81_i112
#ISCELL
  mstr_standard offpage *
  page81_i113
#ISCELL
  mstr_standard tap *
  page81_i114
#ISCELL
  mstr_standard tap *
  page81_i115
#ISCELL
  mstr_standard tap *
  page81_i116
#ISCELL
  mstr_standard tap *
  page81_i117
#ISCELL
  mstr_standard tap *
  page81_i118
#ISCELL
  mstr_standard tap *
  page81_i119
#ISCELL
  mstr_standard tap *
  page81_i12
#ISCELL
  mstr_standard tap *
  page81_i120
#ISCELL
  mstr_standard tap *
  page81_i121
#ISCELL
  mstr_standard tap *
  page81_i122
#ISCELL
  mstr_standard tap *
  page81_i123
#ISCELL
  mstr_standard tap *
  page81_i124
#ISCELL
  mstr_standard tap *
  page81_i125
#ISCELL
  mstr_standard tap *
  page81_i126
#ISCELL
  mstr_standard tap *
  page81_i127
#ISCELL
  mstr_standard tap *
  page81_i128
#ISCELL
  mstr_standard tap *
  page81_i129
#ISCELL
  mstr_standard tap *
  page81_i13
#ISCELL
  mstr_standard tap *
  page81_i130
#ISCELL
  mstr_standard tap *
  page81_i131
#ISCELL
  mstr_standard tap *
  page81_i132
#ISCELL
  mstr_standard offpage *
  page81_i133
#ISCELL
  mstr_standard tap *
  page81_i134
#ISCELL
  mstr_standard tap *
  page81_i135
#ISCELL
  mstr_standard offpage *
  page81_i136
#ISCELL
  mstr_standard tap *
  page81_i137
#ISCELL
  mstr_standard offpage *
  page81_i138
#ISCELL
  mstr_standard offpage *
  page81_i139
#ISCELL
  mstr_standard tap *
  page81_i14
#ISCELL
  mstr_standard tap *
  page81_i140
#ISCELL
  mstr_standard tap *
  page81_i141
#ISCELL
  mstr_standard tap *
  page81_i142
#ISCELL
  mstr_standard tap *
  page81_i143
#ISCELL
  mstr_standard tap *
  page81_i144
#ISCELL
  mstr_standard tap *
  page81_i145
#ISCELL
  mstr_standard tap *
  page81_i146
#ISCELL
  mstr_standard offpage *
  page81_i147
#ISCELL
  mstr_standard offpage *
  page81_i148
#ISCELL
  mstr_standard offpage *
  page81_i149
#ISCELL
  mstr_standard tap *
  page81_i15
#ISCELL
  mstr_standard offpage *
  page81_i150
#ISCELL
  mstr_standard tap *
  page81_i152
#ISCELL
  mstr_standard tap *
  page81_i153
#ISCELL
  mstr_standard tap *
  page81_i154
#ISCELL
  mstr_standard tap *
  page81_i155
#ISCELL
  mstr_standard offpage *
  page81_i156
#ISCELL
  mstr_standard offpage *
  page81_i157
#ISCELL
  mstr_standard tap *
  page81_i158
#ISCELL
  mstr_standard tap *
  page81_i159
#ISCELL
  mstr_standard tap *
  page81_i16
#ISCELL
  mstr_standard tap *
  page81_i160
#ISCELL
  mstr_standard tap *
  page81_i161
#ISCELL
  mstr_standard tap *
  page81_i162
#ISCELL
  mstr_standard tap *
  page81_i163
#ISCELL
  mstr_standard tap *
  page81_i164
#ISCELL
  mstr_standard offpage *
  page81_i165
#ISCELL
  mstr_standard offpage *
  page81_i166
#ISCELL
  mstr_standard offpage *
  page81_i167
#ISCELL
  mstr_standard tap *
  page81_i168
#CELL
  mstr_sconn sconn288_h44441004 *
  page81_i169
#ISCELL
  mstr_symbols pvddq_ghj *
  page81_i17
#ISCELL
  mstr_symbols gnd *
  page81_i170
#ISCELL
  mstr_standard offpage *
  page81_i171
#ISCELL
  mstr_standard offpage *
  page81_i172
#ISCELL
  mstr_standard offpage *
  page81_i173
#ISCELL
  mstr_symbols gnd *
  page81_i175
#ISCELL
  mstr_standard offpage *
  page81_i176
#ISCELL
  mstr_symbols gnd *
  page81_i177
#CELL
  dev_discrete cap_a *
  page81_i178
#ISCELL
  mstr_symbols pvpp_ghj *
  page81_i179
#ISCELL
  mstr_symbols pvtt_ghj *
  page81_i18
#ISCELL
  mstr_symbols pvpp_ghj *
  page81_i180
#ISCELL
  mstr_standard offpage *
  page81_i181
#CELL
  mstr_sconn sconn288_h44441004 *
  page81_i185
#CELL
  mstr_sconn sconn288_h44441004 *
  page81_i186
#ISCELL
  mstr_symbols p12v_nvdimm_ghj *
  page81_i187
#ISCELL
  mstr_standard offpage *
  page81_i2
#ISCELL
  mstr_standard tap *
  page81_i20
#ISCELL
  mstr_standard tap *
  page81_i21
#ISCELL
  mstr_standard tap *
  page81_i22
#ISCELL
  mstr_standard tap *
  page81_i23
#ISCELL
  mstr_standard tap *
  page81_i24
#ISCELL
  mstr_standard tap *
  page81_i25
#ISCELL
  mstr_standard tap *
  page81_i26
#ISCELL
  mstr_standard tap *
  page81_i27
#ISCELL
  mstr_standard tap *
  page81_i28
#ISCELL
  mstr_standard tap *
  page81_i29
#ISCELL
  mstr_standard tap *
  page81_i3
#ISCELL
  mstr_standard tap *
  page81_i30
#ISCELL
  mstr_standard tap *
  page81_i31
#ISCELL
  mstr_standard tap *
  page81_i32
#ISCELL
  mstr_standard tap *
  page81_i33
#ISCELL
  mstr_standard tap *
  page81_i34
#ISCELL
  mstr_standard tap *
  page81_i35
#ISCELL
  mstr_standard tap *
  page81_i36
#ISCELL
  mstr_standard tap *
  page81_i37
#ISCELL
  mstr_standard tap *
  page81_i38
#ISCELL
  mstr_standard tap *
  page81_i39
#ISCELL
  mstr_standard tap *
  page81_i4
#ISCELL
  mstr_standard tap *
  page81_i40
#ISCELL
  mstr_standard tap *
  page81_i41
#ISCELL
  mstr_symbols gnd *
  page81_i44
#ISCELL
  mstr_standard offpage *
  page81_i45
#ISCELL
  mstr_standard tap *
  page81_i46
#ISCELL
  mstr_standard tap *
  page81_i47
#ISCELL
  mstr_standard tap *
  page81_i48
#ISCELL
  mstr_standard tap *
  page81_i49
#ISCELL
  mstr_standard tap *
  page81_i5
#ISCELL
  mstr_standard tap *
  page81_i50
#ISCELL
  mstr_standard tap *
  page81_i51
#ISCELL
  mstr_standard tap *
  page81_i52
#ISCELL
  mstr_standard tap *
  page81_i53
#ISCELL
  mstr_standard tap *
  page81_i54
#ISCELL
  mstr_standard tap *
  page81_i55
#ISCELL
  mstr_standard tap *
  page81_i56
#ISCELL
  mstr_standard tap *
  page81_i57
#ISCELL
  mstr_standard tap *
  page81_i58
#ISCELL
  mstr_standard tap *
  page81_i59
#ISCELL
  mstr_standard tap *
  page81_i6
#ISCELL
  mstr_standard tap *
  page81_i60
#ISCELL
  mstr_standard tap *
  page81_i61
#ISCELL
  mstr_standard tap *
  page81_i62
#ISCELL
  mstr_standard tap *
  page81_i63
#ISCELL
  mstr_standard tap *
  page81_i64
#ISCELL
  mstr_standard tap *
  page81_i65
#ISCELL
  mstr_standard tap *
  page81_i66
#CELL
  mstr_sconn sconn288_h44441004 *
  page81_i67
#ISCELL
  mstr_standard tap *
  page81_i68
#ISCELL
  mstr_standard tap *
  page81_i69
#ISCELL
  mstr_standard tap *
  page81_i7
#ISCELL
  mstr_standard tap *
  page81_i70
#ISCELL
  mstr_standard tap *
  page81_i71
#ISCELL
  mstr_standard tap *
  page81_i72
#ISCELL
  mstr_standard tap *
  page81_i73
#ISCELL
  mstr_standard tap *
  page81_i74
#ISCELL
  mstr_standard tap *
  page81_i75
#ISCELL
  mstr_standard tap *
  page81_i76
#ISCELL
  mstr_standard tap *
  page81_i77
#ISCELL
  mstr_standard tap *
  page81_i78
#ISCELL
  mstr_standard tap *
  page81_i79
#ISCELL
  mstr_standard tap *
  page81_i8
#ISCELL
  mstr_standard tap *
  page81_i80
#ISCELL
  mstr_standard tap *
  page81_i81
#ISCELL
  mstr_standard tap *
  page81_i82
#ISCELL
  mstr_standard tap *
  page81_i83
#ISCELL
  mstr_standard tap *
  page81_i84
#ISCELL
  mstr_standard tap *
  page81_i85
#ISCELL
  mstr_standard tap *
  page81_i86
#ISCELL
  mstr_standard tap *
  page81_i87
#ISCELL
  mstr_standard tap *
  page81_i88
#ISCELL
  mstr_standard tap *
  page81_i89
#ISCELL
  mstr_standard tap *
  page81_i9
#ISCELL
  mstr_standard tap *
  page81_i90
#ISCELL
  mstr_standard tap *
  page81_i91
#ISCELL
  mstr_standard tap *
  page81_i92
#ISCELL
  mstr_standard tap *
  page81_i93
#ISCELL
  mstr_standard tap *
  page81_i94
#ISCELL
  mstr_standard tap *
  page81_i95
#ISCELL
  mstr_standard tap *
  page81_i96
#ISCELL
  mstr_standard tap *
  page81_i97
#ISCELL
  mstr_standard tap *
  page81_i98
#ISCELL
  mstr_standard tap *
  page81_i99
